# T6G (Grand Teton) — schematic netlist excerpt (pin names and nets, part order shuffled) for the footprints in the layout excerpt that follows; sources: Cadence DE-HDL packaged netlist, KiCad conversion of 04192023_DAF0TMB3IC0_F0TG_MB_C_brd_V02_OCP.brd

R790  Q_RES  0 5% EMPTY  pkg 0402LF  page 160 : A = SMB_CPU0_CPU1_APML_BUF1_SDA ; B = SMB_CPU0_CPU1_APML_BUF1_SDA_R1
PR388  Q_RES  0 5% CHIP  pkg 0402LF  page 224 : A = P12V_AUX ; B = PVDD11_S3_P1_VINSEN

(kicad_pcb
	(version 20260206)
	(generator "pcbnew")
	(generator_version "10.0")
	(general
		(thickness 1.6)
		(legacy_teardrops no)
	)
	(paper "A4")
	(title_block
		(title "04192023_DAF0TMB3IC0_F0TG_MB_C_brd_V02_OCP.brd")
		(comment 1 "Grand Teton / footprints 8208-8209 of 8354")
	)
	(layers
		(0 "F.Cu" signal "TOP")
		(4 "In1.Cu" signal "GND")
		(6 "In2.Cu" signal "IN1")
		(8 "In3.Cu" signal "GND1")
		(10 "In4.Cu" signal "IN2")
		(12 "In5.Cu" signal "GND2")
		(14 "In6.Cu" signal "IN3")
		(16 "In7.Cu" signal "GND3")
		(18 "In8.Cu" signal "VCC")
		(20 "In9.Cu" signal "VCC1")
		(22 "In10.Cu" signal "GND4")
		(24 "In11.Cu" signal "IN4")
		(26 "In12.Cu" signal "GND5")
		(28 "In13.Cu" signal "IN5")
		(30 "In14.Cu" signal "GND6")
		(32 "In15.Cu" signal "IN6")
		(34 "In16.Cu" signal "GND7")
		(2 "B.Cu" signal "BOTTOM")
		(9 "F.Adhes" user "F.Adhesive")
		(11 "B.Adhes" user "B.Adhesive")
		(13 "F.Paste" user "Package Geometry/Pastemask Top")
		(15 "B.Paste" user "Package Geometry/Pastemask Bottom")
		(5 "F.SilkS" user "Ref Des/Silkscreen Top")
		(7 "B.SilkS" user "Ref Des/Silkscreen Bottom")
		(1 "F.Mask" user "Board Geometry/Soldermask Top")
		(3 "B.Mask" user "Board Geometry/Soldermask Bottom")
		(17 "Dwgs.User" user "User.Drawings")
		(19 "Cmts.User" user "User.Comments")
		(21 "Eco1.User" user "User.Eco1")
		(23 "Eco2.User" user "User.Eco2")
		(25 "Edge.Cuts" user "Board Geometry/Outline")
		(27 "Margin" user)
		(31 "F.CrtYd" user "Package Geometry/Place Bound Top")
		(29 "B.CrtYd" user "Package Geometry/Place Bound Bottom")
		(35 "F.Fab" user "Ref Des/Assembly Top")
		(33 "B.Fab" user "Ref Des/Assembly Bottom")
	)
	(footprint ""
		(layer "B.Cu")
		(at 239.649 -227.203 180)
		(property "Reference" "R790"
			(at 0 0 0)
			(layer "B.SilkS")
			(hide yes)
			(effects
				(font
					(size 1.27 1.27)
				)
				(justify mirror)
			)
		)
		(property "Value" ""
			(at 0 0 0)
			(layer "B.Fab")
			(effects
				(font
					(size 1.27 1.27)
				)
				(justify mirror)
			)
		)
		(duplicate_pad_numbers_are_jumpers no)
		(fp_line
			(start 0.7874 0.4064)
			(end 0.7874 -0.4064)
			(stroke
				(width 0.1524)
				(type default)
			)
			(layer "B.SilkS")
		)
		(fp_line
			(start 0.7874 -0.4064)
			(end -0.7874 -0.4064)
			(stroke
				(width 0.1524)
				(type default)
			)
			(layer "B.SilkS")
		)
		(fp_line
			(start -0.7874 0.4064)
			(end 0.7874 0.4064)
			(stroke
				(width 0.1524)
				(type default)
			)
			(layer "B.SilkS")
		)
		(fp_line
			(start -0.7874 -0.4064)
			(end -0.7874 0.4064)
			(stroke
				(width 0.1524)
				(type default)
			)
			(layer "B.SilkS")
		)
		(fp_line
			(start 0.67945 0.3048)
			(end 0.67945 -0.305054)
			(stroke
				(width 0.1)
				(type default)
			)
			(layer "B.Fab")
		)
		(fp_line
			(start 0.67945 -0.305054)
			(end 0.12065 -0.305054)
			(stroke
				(width 0.1)
				(type default)
			)
			(layer "B.Fab")
		)
		(fp_line
			(start 0.12065 0.3048)
			(end 0.67945 0.3048)
			(stroke
				(width 0.1)
				(type default)
			)
			(layer "B.Fab")
		)
		(fp_line
			(start 0.12065 0.2794)
			(end 0.12065 0.3048)
			(stroke
				(width 0.1)
				(type default)
			)
			(layer "B.Fab")
		)
		(fp_line
			(start 0.12065 -0.2794)
			(end -0.12065 -0.2794)
			(stroke
				(width 0.1)
				(type default)
			)
			(layer "B.Fab")
		)
		(fp_line
			(start 0.12065 -0.305054)
			(end 0.12065 -0.2794)
			(stroke
				(width 0.1)
				(type default)
			)
			(layer "B.Fab")
		)
		(fp_line
			(start -0.120396 0.3048)
			(end -0.120396 0.2794)
			(stroke
				(width 0.1)
				(type default)
			)
			(layer "B.Fab")
		)
		(fp_line
			(start -0.120396 0.2794)
			(end 0.12065 0.2794)
			(stroke
				(width 0.1)
				(type default)
			)
			(layer "B.Fab")
		)
		(fp_line
			(start -0.12065 -0.2794)
			(end -0.12065 -0.3048)
			(stroke
				(width 0.1)
				(type default)
			)
			(layer "B.Fab")
		)
		(fp_line
			(start -0.12065 -0.3048)
			(end -0.67945 -0.3048)
			(stroke
				(width 0.1)
				(type default)
			)
			(layer "B.Fab")
		)
		(fp_line
			(start -0.67945 0.3048)
			(end -0.120396 0.3048)
			(stroke
				(width 0.1)
				(type default)
			)
			(layer "B.Fab")
		)
		(fp_line
			(start -0.67945 -0.3048)
			(end -0.67945 0.3048)
			(stroke
				(width 0.1)
				(type default)
			)
			(layer "B.Fab")
		)
		(pad "1" smd circle
			(at 0.40005 0)
			(size 0 0)
			(layers "B.Cu" "B.Mask" "B.Paste")
			(net "SMB_CPU0_CPU1_APML_BUF1_SDA")
		)
		(pad "2" smd circle
			(at -0.40005 0)
			(size 0 0)
			(layers "B.Cu" "B.Mask" "B.Paste")
			(net "SMB_CPU0_CPU1_APML_BUF1_SDA_R1")
		)
	)
	(footprint ""
		(layer "B.Cu")
		(at 167.936418 -350.732344)
		(property "Reference" "PR388"
			(at 0 0 0)
			(layer "B.SilkS")
			(hide yes)
			(effects
				(font
					(size 1.27 1.27)
				)
				(justify mirror)
			)
		)
		(property "Value" ""
			(at 0 0 0)
			(layer "B.Fab")
			(effects
				(font
					(size 1.27 1.27)
				)
				(justify mirror)
			)
		)
		(duplicate_pad_numbers_are_jumpers no)
		(fp_line
			(start -0.7874 -0.4064)
			(end -0.7874 0.4064)
			(stroke
				(width 0.1524)
				(type default)
			)
			(layer "B.SilkS")
		)
		(fp_line
			(start -0.7874 0.4064)
			(end 0.7874 0.4064)
			(stroke
				(width 0.1524)
				(type default)
			)
			(layer "B.SilkS")
		)
		(fp_line
			(start 0.7874 -0.4064)
			(end -0.7874 -0.4064)
			(stroke
				(width 0.1524)
				(type default)
			)
			(layer "B.SilkS")
		)
		(fp_line
			(start 0.7874 0.4064)
			(end 0.7874 -0.4064)
			(stroke
				(width 0.1524)
				(type default)
			)
			(layer "B.SilkS")
		)
		(fp_line
			(start -0.67945 -0.3048)
			(end -0.67945 0.3048)
			(stroke
				(width 0.1)
				(type default)
			)
			(layer "B.Fab")
		)
		(fp_line
			(start -0.67945 0.3048)
			(end -0.120396 0.3048)
			(stroke
				(width 0.1)
				(type default)
			)
			(layer "B.Fab")
		)
		(fp_line
			(start -0.12065 -0.3048)
			(end -0.67945 -0.3048)
			(stroke
				(width 0.1)
				(type default)
			)
			(layer "B.Fab")
		)
		(fp_line
			(start -0.12065 -0.2794)
			(end -0.12065 -0.3048)
			(stroke
				(width 0.1)
				(type default)
			)
			(layer "B.Fab")
		)
		(fp_line
			(start -0.120396 0.2794)
			(end 0.12065 0.2794)
			(stroke
				(width 0.1)
				(type default)
			)
			(layer "B.Fab")
		)
		(fp_line
			(start -0.120396 0.3048)
			(end -0.120396 0.2794)
			(stroke
				(width 0.1)
				(type default)
			)
			(layer "B.Fab")
		)
		(fp_line
			(start 0.12065 -0.305054)
			(end 0.12065 -0.2794)
			(stroke
				(width 0.1)
				(type default)
			)
			(layer "B.Fab")
		)
		(fp_line
			(start 0.12065 -0.2794)
			(end -0.12065 -0.2794)
			(stroke
				(width 0.1)
				(type default)
			)
			(layer "B.Fab")
		)
		(fp_line
			(start 0.12065 0.2794)
			(end 0.12065 0.3048)
			(stroke
				(width 0.1)
				(type default)
			)
			(layer "B.Fab")
		)
		(fp_line
			(start 0.12065 0.3048)
			(end 0.67945 0.3048)
			(stroke
				(width 0.1)
				(type default)
			)
			(layer "B.Fab")
		)
		(fp_line
			(start 0.67945 -0.305054)
			(end 0.12065 -0.305054)
			(stroke
				(width 0.1)
				(type default)
			)
			(layer "B.Fab")
		)
		(fp_line
			(start 0.67945 0.3048)
			(end 0.67945 -0.305054)
			(stroke
				(width 0.1)
				(type default)
			)
			(layer "B.Fab")
		)
		(pad "1" smd circle
			(at 0.40005 0 180)
			(size 0 0)
			(layers "B.Cu" "B.Mask" "B.Paste")
			(net "P12V_AUX")
		)
		(pad "2" smd circle
			(at -0.40005 0 180)
			(size 0 0)
			(layers "B.Cu" "B.Mask" "B.Paste")
			(net "PVDD11_S3_P1_VINSEN")
		)
	)
)
